(kicad_pcb
	(version 20241229)
	(generator "pcbnew")
	(generator_version "9.0")
	(general
		(thickness 1.552)
		(legacy_teardrops no)
	)
	(paper "A4")
	(title_block
		(date "2023-07-25")
		(rev "1.1.4")
		(comment 9 "footprints 337-340 of 379")
	)
	(layers
		(0 "F.Cu" signal)
		(4 "In1.Cu" signal)
		(6 "In2.Cu" signal)
		(8 "In3.Cu" signal)
		(10 "In4.Cu" signal)
		(12 "In5.Cu" signal)
		(14 "In6.Cu" signal)
		(2 "B.Cu" signal)
		(9 "F.Adhes" user "F.Adhesive")
		(11 "B.Adhes" user "B.Adhesive")
		(13 "F.Paste" user)
		(15 "B.Paste" user)
		(5 "F.SilkS" user "F.Silkscreen")
		(7 "B.SilkS" user "B.Silkscreen")
		(1 "F.Mask" user)
		(3 "B.Mask" user)
		(17 "Dwgs.User" user "User.Drawings")
		(19 "Cmts.User" user "User.Comments")
		(21 "Eco1.User" user "User.Eco1")
		(23 "Eco2.User" user "User.Eco2")
		(25 "Edge.Cuts" user)
		(27 "Margin" user)
		(31 "F.CrtYd" user "F.Courtyard")
		(29 "B.CrtYd" user "B.Courtyard")
		(35 "F.Fab" user)
		(33 "B.Fab" user)
	)
	(footprint "antmicro-footprints:R_Array_4x0402"
		(layer "B.Cu")
		(at 124.36 57.44 180)
		(property "Reference" "R49"
			(at -0.97 1 0)
			(layer "B.SilkS")
			(effects
				(font
					(size 0.65 0.65)
					(thickness 0.15)
				)
				(justify left bottom mirror)
			)
		)
		(property "Value" "R_4x51R_0402_array"
			(at -1.5 -2 0)
			(layer "B.Fab")
			(hide yes)
			(effects
				(font
					(size 0.7 0.7)
					(thickness 0.15)
				)
				(justify left bottom mirror)
			)
		)
		(property "Datasheet" "http://industrial.panasonic.com/cdbs/www-data/pdf/AOC0000/AOC0000C14.pdf"
			(at 0 0 180)
			(layer "F.Fab")
			(hide yes)
			(effects
				(font
					(size 1.27 1.27)
					(thickness 0.15)
				)
			)
		)
		(property "Description" "Fixed Network Resistor, 51 ohm, Isolated, 4 Resistors, 0804 [2010 Metric], Convex, ± 5%"
			(at 0 0 180)
			(layer "F.Fab")
			(hide yes)
			(effects
				(font
					(size 1.27 1.27)
					(thickness 0.15)
				)
			)
		)
		(property "Author" "Antmicro"
			(at 248.72 114.88 0)
			(layer "B.Fab")
			(hide yes)
			(effects
				(font
					(size 1 1)
					(thickness 0.15)
				)
				(justify mirror)
			)
		)
		(property "License" "Apache-2.0"
			(at 248.72 114.88 0)
			(layer "B.Fab")
			(hide yes)
			(effects
				(font
					(size 1 1)
					(thickness 0.15)
				)
				(justify mirror)
			)
		)
		(property "MPN" "EXB28V510JX"
			(at 248.72 114.88 0)
			(layer "B.Fab")
			(hide yes)
			(effects
				(font
					(size 1 1)
					(thickness 0.15)
				)
				(justify mirror)
			)
		)
		(property "Manufacturer" "Panasonic"
			(at 248.72 114.88 0)
			(layer "B.Fab")
			(hide yes)
			(effects
				(font
					(size 1 1)
					(thickness 0.15)
				)
				(justify mirror)
			)
		)
		(property "Val" "R_4x51R_0402"
			(at 248.72 114.88 0)
			(layer "B.Fab")
			(hide yes)
			(effects
				(font
					(size 1 1)
					(thickness 0.15)
				)
				(justify mirror)
			)
		)
		(sheetname "/DDR3/")
		(sheetfile "ddr3.kicad_sch")
		(attr smd)
		(fp_line
			(start 1.167 -0.498)
			(end 1.167 0.5)
			(stroke
				(width 0.15)
				(type solid)
			)
			(layer "B.SilkS")
		)
		(fp_line
			(start -1.17 0.5)
			(end -1.17 -0.498)
			(stroke
				(width 0.15)
				(type solid)
			)
			(layer "B.SilkS")
		)
		(fp_rect
			(start -1.2 0.9)
			(end 1.2 -0.9)
			(stroke
				(width 0.05)
				(type solid)
			)
			(fill no)
			(layer "B.CrtYd")
		)
		(fp_line
			(start 0.998 0.5)
			(end 0.998 -0.498)
			(stroke
				(width 0.15)
				(type solid)
			)
			(layer "B.Fab")
		)
		(fp_line
			(start 0.998 -0.498)
			(end -1 -0.498)
			(stroke
				(width 0.15)
				(type solid)
			)
			(layer "B.Fab")
		)
		(fp_line
			(start -1 0.5)
			(end 0.998 0.5)
			(stroke
				(width 0.15)
				(type solid)
			)
			(layer "B.Fab")
		)
		(fp_line
			(start -1 -0.498)
			(end -1 0.5)
			(stroke
				(width 0.15)
				(type solid)
			)
			(layer "B.Fab")
		)
		(pad "1" smd roundrect
			(at -0.802 -0.45 180)
			(size 0.4 0.5)
			(layers "B.Cu" "B.Mask" "B.Paste")
			(roundrect_rratio 0.25)
			(net 158 "/DDR3/DDR3_A13")
			(pinfunction "R1.1")
			(pintype "passive")
		)
		(pad "2" smd roundrect
			(at -0.272 -0.45 180)
			(size 0.4 0.5)
			(layers "B.Cu" "B.Mask" "B.Paste")
			(roundrect_rratio 0.25)
			(net 144 "/DDR3/DDR3_A2")
			(pinfunction "R2.1")
			(pintype "passive")
		)
		(pad "3" smd roundrect
			(at 0.27 -0.45 180)
			(size 0.4 0.5)
			(layers "B.Cu" "B.Mask" "B.Paste")
			(roundrect_rratio 0.25)
			(net 146 "/DDR3/DDR3_A3")
			(pinfunction "R3.1")
			(pintype "passive")
		)
		(pad "4" smd roundrect
			(at 0.8 -0.45 180)
			(size 0.4 0.5)
			(layers "B.Cu" "B.Mask" "B.Paste")
			(roundrect_rratio 0.25)
			(net 147 "/DDR3/DDR3_A0")
			(pinfunction "R4.1")
			(pintype "passive")
		)
		(pad "5" smd roundrect
			(at 0.8 0.452 180)
			(size 0.4 0.5)
			(layers "B.Cu" "B.Mask" "B.Paste")
			(roundrect_rratio 0.25)
			(net 6 "Vtt")
			(pinfunction "R4.2")
			(pintype "passive")
		)
		(pad "6" smd roundrect
			(at 0.27 0.452 180)
			(size 0.4 0.5)
			(layers "B.Cu" "B.Mask" "B.Paste")
			(roundrect_rratio 0.25)
			(net 6 "Vtt")
			(pinfunction "R3.2")
			(pintype "passive")
		)
		(pad "7" smd roundrect
			(at -0.272 0.452 180)
			(size 0.4 0.5)
			(layers "B.Cu" "B.Mask" "B.Paste")
			(roundrect_rratio 0.25)
			(net 6 "Vtt")
			(pinfunction "R2.2")
			(pintype "passive")
		)
		(pad "8" smd roundrect
			(at -0.802 0.452 180)
			(size 0.4 0.5)
			(layers "B.Cu" "B.Mask" "B.Paste")
			(roundrect_rratio 0.25)
			(net 6 "Vtt")
			(pinfunction "R1.2")
			(pintype "passive")
		)
	)
	(footprint "antmicro-footprints:FB_0603_1608Metric"
		(layer "B.Cu")
		(at 135.13 98.04)
		(property "Reference" "FB5"
			(at 3.4 0.35 180)
			(layer "B.SilkS")
			(effects
				(font
					(size 0.65 0.65)
					(thickness 0.15)
				)
				(justify left bottom mirror)
			)
		)
		(property "Value" "FB_120Z_2A_0603"
			(at 0 -1.5 180)
			(layer "B.Fab")
			(hide yes)
			(effects
				(font
					(size 0.7 0.7)
					(thickness 0.15)
				)
				(justify left bottom mirror)
			)
		)
		(property "Datasheet" "https://www.murata.com/en-us/products/productdata/8796738650142/ENFA0003.pdf"
			(at 0 0 0)
			(layer "F.Fab")
			(hide yes)
			(effects
				(font
					(size 1.27 1.27)
					(thickness 0.15)
				)
			)
		)
		(property "Description" "Ferrite Bead, 0603 [1608 Metric], 120 ohm, 2 A, BLM18P, 0.05 ohm, ± 25%, DC power line"
			(at 0 0 0)
			(layer "F.Fab")
			(hide yes)
			(effects
				(font
					(size 1.27 1.27)
					(thickness 0.15)
				)
			)
		)
		(property "Author" "Antmicro"
			(at 0 0 0)
			(layer "B.Fab")
			(hide yes)
			(effects
				(font
					(size 1 1)
					(thickness 0.15)
				)
				(justify mirror)
			)
		)
		(property "License" "Apache-2.0"
			(at 0 0 0)
			(layer "B.Fab")
			(hide yes)
			(effects
				(font
					(size 1 1)
					(thickness 0.15)
				)
				(justify mirror)
			)
		)
		(property "MPN" "BLM18PG121SN1D"
			(at 0 0 0)
			(layer "B.Fab")
			(hide yes)
			(effects
				(font
					(size 1 1)
					(thickness 0.15)
				)
				(justify mirror)
			)
		)
		(property "Manufacturer" "Murata"
			(at 0 0 0)
			(layer "B.Fab")
			(hide yes)
			(effects
				(font
					(size 1 1)
					(thickness 0.15)
				)
				(justify mirror)
			)
		)
		(property "Val" "120Z/2A"
			(at 0 0 0)
			(unlocked yes)
			(layer "B.Fab")
			(hide yes)
			(effects
				(font
					(size 1 1)
					(thickness 0.15)
				)
				(justify mirror)
			)
		)
		(property "Current" ""
			(at 0 0 0)
			(unlocked yes)
			(layer "B.Fab")
			(hide yes)
			(effects
				(font
					(size 1 1)
					(thickness 0.15)
				)
				(justify mirror)
			)
		)
		(sheetname "/FPGA Power/")
		(sheetfile "FPGA_Power.kicad_sch")
		(attr smd)
		(fp_line
			(start -0.15 -0.4)
			(end 0.15 -0.4)
			(stroke
				(width 0.15)
				(type solid)
			)
			(layer "B.SilkS")
		)
		(fp_line
			(start -0.15 0.4)
			(end 0.15 0.4)
			(stroke
				(width 0.15)
				(type solid)
			)
			(layer "B.SilkS")
		)
		(fp_rect
			(start -1.25 0.65)
			(end 1.25 -0.65)
			(stroke
				(width 0.05)
				(type solid)
			)
			(fill no)
			(layer "B.CrtYd")
		)
		(fp_line
			(start -0.803 -0.406)
			(end -0.803 0.408)
			(stroke
				(width 0.15)
				(type solid)
			)
			(layer "B.Fab")
		)
		(fp_line
			(start 0.8 -0.406)
			(end -0.803 -0.406)
			(stroke
				(width 0.15)
				(type solid)
			)
			(layer "B.Fab")
		)
		(fp_line
			(start 0.8 0.408)
			(end -0.803 0.408)
			(stroke
				(width 0.15)
				(type solid)
			)
			(layer "B.Fab")
		)
		(fp_line
			(start 0.8 0.408)
			(end 0.8 -0.406)
			(stroke
				(width 0.15)
				(type solid)
			)
			(layer "B.Fab")
		)
		(fp_text user "${REFERENCE}"
			(at -1.653 -4.6 180)
			(layer "B.Fab")
			(effects
				(font
					(size 0.7 0.7)
					(thickness 0.15)
				)
				(justify left bottom mirror)
			)
		)
		(fp_text user "Author: Antmicro"
			(at -1.653 -3.162 180)
			(layer "B.Fab")
			(effects
				(font
					(size 0.7 0.7)
					(thickness 0.15)
				)
				(justify left bottom mirror)
			)
		)
		(fp_text user "License: Apache-2.0"
			(at -1.653 -5.9 180)
			(layer "B.Fab")
			(effects
				(font
					(size 0.7 0.7)
					(thickness 0.15)
				)
				(justify left bottom mirror)
			)
		)
		(pad "1" smd roundrect
			(at -0.7 0)
			(size 0.8 1)
			(layers "B.Cu" "B.Mask" "B.Paste")
			(roundrect_rratio 0.2)
			(net 13 "/FPGA Power/VCC_PLLDPHY")
			(pintype "passive")
		)
		(pad "2" smd roundrect
			(at 0.7 0)
			(size 0.8 1)
			(layers "B.Cu" "B.Mask" "B.Paste")
			(roundrect_rratio 0.2)
			(net 49 "1V0_Clean")
			(pintype "passive")
		)
	)
	(footprint "antmicro-footprints:R_0402_1005Metric"
		(layer "B.Cu")
		(at 156.23 65.35 90)
		(descr "Resistor SMD 0402")
		(tags "resistor SMD 0402")
		(property "Reference" "R64"
			(at 2.91 0.4 270)
			(layer "B.SilkS")
			(effects
				(font
					(size 0.65 0.65)
					(thickness 0.15)
				)
				(justify left bottom mirror)
			)
		)
		(property "Value" "R_10k_0402"
			(at 0 -1.4 270)
			(layer "B.Fab")
			(hide yes)
			(effects
				(font
					(size 0.7 0.7)
					(thickness 0.15)
				)
				(justify left bottom mirror)
			)
		)
		(property "Datasheet" "https://www.bourns.com/docs/product-datasheets/cr.pdf"
			(at 0 0 90)
			(layer "F.Fab")
			(hide yes)
			(effects
				(font
					(size 1.27 1.27)
					(thickness 0.15)
				)
			)
		)
		(property "Description" "SMD Chip Resistor, 10 kohm, ± 1%, 62.5 mW, 0402 [1005 Metric], Thick Film, General Purpose"
			(at 0 0 90)
			(layer "F.Fab")
			(hide yes)
			(effects
				(font
					(size 1.27 1.27)
					(thickness 0.15)
				)
			)
		)
		(property "Author" "Antmicro"
			(at 221.58 -90.88 0)
			(layer "B.Fab")
			(hide yes)
			(effects
				(font
					(size 1 1)
					(thickness 0.15)
				)
				(justify mirror)
			)
		)
		(property "License" "Apache-2.0"
			(at 221.58 -90.88 0)
			(layer "B.Fab")
			(hide yes)
			(effects
				(font
					(size 1 1)
					(thickness 0.15)
				)
				(justify mirror)
			)
		)
		(property "MPN" "CR0402-FX-1002GLF"
			(at 221.58 -90.88 0)
			(layer "B.Fab")
			(hide yes)
			(effects
				(font
					(size 1 1)
					(thickness 0.15)
				)
				(justify mirror)
			)
		)
		(property "Manufacturer" "Bourns"
			(at 221.58 -90.88 0)
			(layer "B.Fab")
			(hide yes)
			(effects
				(font
					(size 1 1)
					(thickness 0.15)
				)
				(justify mirror)
			)
		)
		(property "Tolerance" "1%"
			(at 221.58 -90.88 0)
			(layer "B.Fab")
			(hide yes)
			(effects
				(font
					(size 1 1)
					(thickness 0.15)
				)
				(justify mirror)
			)
		)
		(property "Val" "10k"
			(at 221.58 -90.88 0)
			(layer "B.Fab")
			(hide yes)
			(effects
				(font
					(size 1 1)
					(thickness 0.15)
				)
				(justify mirror)
			)
		)
		(sheetname "/Power Supply/")
		(sheetfile "supply.kicad_sch")
		(attr smd)
		(fp_rect
			(start -0.925 0.47)
			(end 0.925 -0.47)
			(stroke
				(width 0.05)
				(type default)
			)
			(fill no)
			(layer "B.CrtYd")
		)
		(fp_rect
			(start -0.5 0.25)
			(end 0.5 -0.25)
			(stroke
				(width 0.15)
				(type solid)
			)
			(fill no)
			(layer "B.Fab")
		)
		(fp_text user "${REFERENCE}"
			(at -0.95 -3.168 270)
			(layer "B.Fab")
			(effects
				(font
					(size 0.7 0.7)
					(thickness 0.15)
				)
				(justify left bottom mirror)
			)
		)
		(fp_text user "Author: Antmicro"
			(at -0.95 -4.169 270)
			(layer "B.Fab")
			(effects
				(font
					(size 0.7 0.7)
					(thickness 0.15)
				)
				(justify left bottom mirror)
			)
		)
		(fp_text user "License: Apache-2.0"
			(at -0.95 -5.169 270)
			(layer "B.Fab")
			(effects
				(font
					(size 0.7 0.7)
					(thickness 0.15)
				)
				(justify left bottom mirror)
			)
		)
		(pad "1" smd roundrect
			(at -0.48 0 90)
			(size 0.59 0.64)
			(layers "B.Cu" "B.Mask" "B.Paste")
			(roundrect_rratio 0.25)
			(net 1 "GND")
			(pintype "passive")
		)
		(pad "2" smd roundrect
			(at 0.48 0 90)
			(size 0.59 0.64)
			(layers "B.Cu" "B.Mask" "B.Paste")
			(roundrect_rratio 0.25)
			(net 382 "Net-(Q2-Pad2)")
			(pintype "passive")
		)
	)
	(footprint "antmicro-footprints:C_0603_1608Metric"
		(layer "B.Cu")
		(at 127.82 82.21)
		(descr "Capacitor SMD 0603")
		(tags "capacitor 0603")
		(property "Reference" "C87"
			(at -3.29 0.43 0)
			(layer "B.SilkS")
			(effects
				(font
					(size 0.65 0.65)
					(thickness 0.15)
				)
				(justify right bottom mirror)
			)
		)
		(property "Value" "C_10u_0603"
			(at 0 -1.6 0)
			(layer "B.Fab")
			(hide yes)
			(effects
				(font
					(size 0.7 0.7)
					(thickness 0.15)
				)
				(justify right bottom mirror)
			)
		)
		(property "Datasheet" "https://www.murata.com/products/productdetail?partno=GRM188R61A106KE69%23"
			(at 0 0 0)
			(layer "F.Fab")
			(hide yes)
			(effects
				(font
					(size 1.27 1.27)
					(thickness 0.15)
				)
			)
		)
		(property "Description" "SMD Multilayer Ceramic Capacitor, 10 µF, 10 V, 0603 [1608 Metric], ± 10%, X5R, GRM Series"
			(at 0 0 0)
			(layer "F.Fab")
			(hide yes)
			(effects
				(font
					(size 1.27 1.27)
					(thickness 0.15)
				)
			)
		)
		(property "Author" "Antmicro"
			(at 0 0 0)
			(layer "B.Fab")
			(hide yes)
			(effects
				(font
					(size 1 1)
					(thickness 0.15)
				)
				(justify mirror)
			)
		)
		(property "License" "Apache-2.0"
			(at 0 0 0)
			(layer "B.Fab")
			(hide yes)
			(effects
				(font
					(size 1 1)
					(thickness 0.15)
				)
				(justify mirror)
			)
		)
		(property "MPN" "GRM188R61A106KE69D"
			(at 0 0 0)
			(layer "B.Fab")
			(hide yes)
			(effects
				(font
					(size 1 1)
					(thickness 0.15)
				)
				(justify mirror)
			)
		)
		(property "Manufacturer" "Murata"
			(at 0 0 0)
			(layer "B.Fab")
			(hide yes)
			(effects
				(font
					(size 1 1)
					(thickness 0.15)
				)
				(justify mirror)
			)
		)
		(property "Val" "10u"
			(at 0 0 0)
			(layer "B.Fab")
			(hide yes)
			(effects
				(font
					(size 1 1)
					(thickness 0.15)
				)
				(justify mirror)
			)
		)
		(property "Voltage" ""
			(at 0 0 0)
			(layer "B.Fab")
			(hide yes)
			(effects
				(font
					(size 1 1)
					(thickness 0.15)
				)
				(justify mirror)
			)
		)
		(property "Dielectric" "template_dielectric"
			(at 0 0 0)
			(unlocked yes)
			(layer "B.Fab")
			(hide yes)
			(effects
				(font
					(size 1 1)
					(thickness 0.15)
				)
				(justify mirror)
			)
		)
		(sheetname "/FPGA Power/")
		(sheetfile "FPGA_Power.kicad_sch")
		(attr smd)
		(fp_line
			(start -0.15 -0.4)
			(end 0.15 -0.4)
			(stroke
				(width 0.15)
				(type solid)
			)
			(layer "B.SilkS")
		)
		(fp_line
			(start -0.15 0.4)
			(end 0.15 0.4)
			(stroke
				(width 0.15)
				(type solid)
			)
			(layer "B.SilkS")
		)
		(fp_rect
			(start -1.25 0.65)
			(end 1.25 -0.65)
			(stroke
				(width 0.05)
				(type solid)
			)
			(fill no)
			(layer "B.CrtYd")
		)
		(fp_rect
			(start -0.8 0.4)
			(end 0.8 -0.4)
			(stroke
				(width 0.15)
				(type solid)
			)
			(fill no)
			(layer "B.Fab")
		)
		(fp_text user "${REFERENCE}"
			(at -1.682 -3.895 180)
			(layer "B.Fab")
			(effects
				(font
					(size 0.7 0.7)
					(thickness 0.15)
				)
				(justify left bottom mirror)
			)
		)
		(fp_text user "Author: Antmicro"
			(at -1.682 -4.894 180)
			(layer "B.Fab")
			(effects
				(font
					(size 0.7 0.7)
					(thickness 0.15)
				)
				(justify left bottom mirror)
			)
		)
		(fp_text user "License: Apache-2.0"
			(at -1.682 -5.895 180)
			(layer "B.Fab")
			(effects
				(font
					(size 0.7 0.7)
					(thickness 0.15)
				)
				(justify left bottom mirror)
			)
		)
		(pad "1" smd roundrect
			(at -0.7 0)
			(size 0.8 1)
			(layers "B.Cu" "B.Mask" "B.Paste")
			(roundrect_rratio 0.2)
			(net 1 "GND")
			(pintype "passive")
		)
		(pad "2" smd roundrect
			(at 0.7 0)
			(size 0.8 1)
			(layers "B.Cu" "B.Mask" "B.Paste")
			(roundrect_rratio 0.2)
			(net 9 "/FPGA Power/VCC_AUX")
			(pintype "passive")
		)
	)
)
